(kicad_pcb
	(version 20260206)
	(generator "pcbnew")
	(generator_version "10.0")
	(general
		(thickness 1.6)
		(legacy_teardrops no)
	)
	(paper "A4")
	(title_block
		(title "03242023_DA0F0TMBIJ0_F0T_Motherboard_J_brd_V01_OCP.brd")
		(comment 1 "Grand Teton / footprints 5533-5539 of 6105")
	)
	(layers
		(0 "F.Cu" signal "TOP")
		(4 "In1.Cu" signal "GND")
		(6 "In2.Cu" signal "IN1")
		(8 "In3.Cu" signal "GND1")
		(10 "In4.Cu" signal "IN2")
		(12 "In5.Cu" signal "GND2")
		(14 "In6.Cu" signal "IN3")
		(16 "In7.Cu" signal "GND3")
		(18 "In8.Cu" signal "VCC")
		(20 "In9.Cu" signal "VCC1")
		(22 "In10.Cu" signal "GND4")
		(24 "In11.Cu" signal "IN4")
		(26 "In12.Cu" signal "GND5")
		(28 "In13.Cu" signal "IN5")
		(30 "In14.Cu" signal "GND6")
		(32 "In15.Cu" signal "IN6")
		(34 "In16.Cu" signal "GND7")
		(2 "B.Cu" signal "BOTTOM")
		(9 "F.Adhes" user "F.Adhesive")
		(11 "B.Adhes" user "B.Adhesive")
		(13 "F.Paste" user "Package Geometry/Pastemask Top")
		(15 "B.Paste" user "Package Geometry/Pastemask Bottom")
		(5 "F.SilkS" user "Ref Des/Silkscreen Top")
		(7 "B.SilkS" user "Ref Des/Silkscreen Bottom")
		(1 "F.Mask" user "Board Geometry/Soldermask Top")
		(3 "B.Mask" user "Board Geometry/Soldermask Bottom")
		(17 "Dwgs.User" user "User.Drawings")
		(19 "Cmts.User" user "User.Comments")
		(21 "Eco1.User" user "User.Eco1")
		(23 "Eco2.User" user "User.Eco2")
		(25 "Edge.Cuts" user "Board Geometry/Outline")
		(27 "Margin" user)
		(31 "F.CrtYd" user "Package Geometry/Place Bound Top")
		(29 "B.CrtYd" user "Package Geometry/Place Bound Bottom")
		(35 "F.Fab" user "Ref Des/Assembly Top")
		(33 "B.Fab" user "Ref Des/Assembly Bottom")
	)
	(footprint ""
		(layer "B.Cu")
		(at 319.635378 -188.41339)
		(property "Reference" "R197"
			(at 0 0 0)
			(layer "B.SilkS")
			(hide yes)
			(effects
				(font
					(size 1.27 1.27)
				)
				(justify mirror)
			)
		)
		(property "Value" ""
			(at 0 0 0)
			(layer "B.Fab")
			(effects
				(font
					(size 1.27 1.27)
				)
				(justify mirror)
			)
		)
		(duplicate_pad_numbers_are_jumpers no)
		(fp_line
			(start -0.7874 -0.4064)
			(end -0.7874 0.4064)
			(stroke
				(width 0.1524)
				(type default)
			)
			(layer "B.SilkS")
		)
		(fp_line
			(start -0.7874 0.4064)
			(end 0.7874 0.4064)
			(stroke
				(width 0.1524)
				(type default)
			)
			(layer "B.SilkS")
		)
		(fp_line
			(start 0.7874 -0.4064)
			(end -0.7874 -0.4064)
			(stroke
				(width 0.1524)
				(type default)
			)
			(layer "B.SilkS")
		)
		(fp_line
			(start 0.7874 0.4064)
			(end 0.7874 -0.4064)
			(stroke
				(width 0.1524)
				(type default)
			)
			(layer "B.SilkS")
		)
		(fp_line
			(start -0.67945 -0.3048)
			(end -0.67945 0.3048)
			(stroke
				(width 0.1)
				(type default)
			)
			(layer "B.Fab")
		)
		(fp_line
			(start -0.67945 0.3048)
			(end -0.120396 0.3048)
			(stroke
				(width 0.1)
				(type default)
			)
			(layer "B.Fab")
		)
		(fp_line
			(start -0.12065 -0.3048)
			(end -0.67945 -0.3048)
			(stroke
				(width 0.1)
				(type default)
			)
			(layer "B.Fab")
		)
		(fp_line
			(start -0.12065 -0.2794)
			(end -0.12065 -0.3048)
			(stroke
				(width 0.1)
				(type default)
			)
			(layer "B.Fab")
		)
		(fp_line
			(start -0.120396 0.2794)
			(end 0.12065 0.2794)
			(stroke
				(width 0.1)
				(type default)
			)
			(layer "B.Fab")
		)
		(fp_line
			(start -0.120396 0.3048)
			(end -0.120396 0.2794)
			(stroke
				(width 0.1)
				(type default)
			)
			(layer "B.Fab")
		)
		(fp_line
			(start 0.12065 -0.305054)
			(end 0.12065 -0.2794)
			(stroke
				(width 0.1)
				(type default)
			)
			(layer "B.Fab")
		)
		(fp_line
			(start 0.12065 -0.2794)
			(end -0.12065 -0.2794)
			(stroke
				(width 0.1)
				(type default)
			)
			(layer "B.Fab")
		)
		(fp_line
			(start 0.12065 0.2794)
			(end 0.12065 0.3048)
			(stroke
				(width 0.1)
				(type default)
			)
			(layer "B.Fab")
		)
		(fp_line
			(start 0.12065 0.3048)
			(end 0.67945 0.3048)
			(stroke
				(width 0.1)
				(type default)
			)
			(layer "B.Fab")
		)
		(fp_line
			(start 0.67945 -0.305054)
			(end 0.12065 -0.305054)
			(stroke
				(width 0.1)
				(type default)
			)
			(layer "B.Fab")
		)
		(fp_line
			(start 0.67945 0.3048)
			(end 0.67945 -0.305054)
			(stroke
				(width 0.1)
				(type default)
			)
			(layer "B.Fab")
		)
		(pad "1" smd circle
			(at 0.40005 0 180)
			(size 0 0)
			(layers "B.Cu" "B.Mask" "B.Paste")
			(net "PVNN_TERM_CPU0")
		)
		(pad "2" smd circle
			(at -0.40005 0 180)
			(size 0 0)
			(layers "B.Cu" "B.Mask" "B.Paste")
			(net "H_CPU0_NMI_LVC1_N")
		)
	)
	(footprint ""
		(layer "B.Cu")
		(at 164.857938 -8.91794 -90)
		(property "Reference" "R2205"
			(at 0 0 90)
			(layer "B.SilkS")
			(hide yes)
			(effects
				(font
					(size 1.27 1.27)
				)
				(justify mirror)
			)
		)
		(property "Value" ""
			(at 0 0 90)
			(layer "B.Fab")
			(effects
				(font
					(size 1.27 1.27)
				)
				(justify mirror)
			)
		)
		(duplicate_pad_numbers_are_jumpers no)
		(fp_line
			(start -0.7874 0.4064)
			(end 0.7874 0.4064)
			(stroke
				(width 0.1524)
				(type default)
			)
			(layer "B.SilkS")
		)
		(fp_line
			(start 0.7874 0.4064)
			(end 0.7874 -0.4064)
			(stroke
				(width 0.1524)
				(type default)
			)
			(layer "B.SilkS")
		)
		(fp_line
			(start -0.7874 -0.4064)
			(end -0.7874 0.4064)
			(stroke
				(width 0.1524)
				(type default)
			)
			(layer "B.SilkS")
		)
		(fp_line
			(start 0.7874 -0.4064)
			(end -0.7874 -0.4064)
			(stroke
				(width 0.1524)
				(type default)
			)
			(layer "B.SilkS")
		)
		(fp_line
			(start -0.67945 0.3048)
			(end -0.120396 0.3048)
			(stroke
				(width 0.1)
				(type default)
			)
			(layer "B.Fab")
		)
		(fp_line
			(start -0.120396 0.3048)
			(end -0.120396 0.2794)
			(stroke
				(width 0.1)
				(type default)
			)
			(layer "B.Fab")
		)
		(fp_line
			(start 0.12065 0.3048)
			(end 0.67945 0.3048)
			(stroke
				(width 0.1)
				(type default)
			)
			(layer "B.Fab")
		)
		(fp_line
			(start 0.67945 0.3048)
			(end 0.67945 -0.305054)
			(stroke
				(width 0.1)
				(type default)
			)
			(layer "B.Fab")
		)
		(fp_line
			(start -0.120396 0.2794)
			(end 0.12065 0.2794)
			(stroke
				(width 0.1)
				(type default)
			)
			(layer "B.Fab")
		)
		(fp_line
			(start 0.12065 0.2794)
			(end 0.12065 0.3048)
			(stroke
				(width 0.1)
				(type default)
			)
			(layer "B.Fab")
		)
		(fp_line
			(start -0.12065 -0.2794)
			(end -0.12065 -0.3048)
			(stroke
				(width 0.1)
				(type default)
			)
			(layer "B.Fab")
		)
		(fp_line
			(start 0.12065 -0.2794)
			(end -0.12065 -0.2794)
			(stroke
				(width 0.1)
				(type default)
			)
			(layer "B.Fab")
		)
		(fp_line
			(start -0.67945 -0.3048)
			(end -0.67945 0.3048)
			(stroke
				(width 0.1)
				(type default)
			)
			(layer "B.Fab")
		)
		(fp_line
			(start -0.12065 -0.3048)
			(end -0.67945 -0.3048)
			(stroke
				(width 0.1)
				(type default)
			)
			(layer "B.Fab")
		)
		(fp_line
			(start 0.12065 -0.305054)
			(end 0.12065 -0.2794)
			(stroke
				(width 0.1)
				(type default)
			)
			(layer "B.Fab")
		)
		(fp_line
			(start 0.67945 -0.305054)
			(end 0.12065 -0.305054)
			(stroke
				(width 0.1)
				(type default)
			)
			(layer "B.Fab")
		)
		(pad "1" smd circle
			(at 0.40005 0 90)
			(size 0 0)
			(layers "B.Cu" "B.Mask" "B.Paste")
			(net "P3V3_AUX")
		)
		(pad "2" smd circle
			(at -0.40005 0 90)
			(size 0 0)
			(layers "B.Cu" "B.Mask" "B.Paste")
			(net "SMB_PCIE0_3V3AUX_SDA")
		)
	)
	(footprint ""
		(layer "B.Cu")
		(at 196.544946 -321.554856 -90)
		(property "Reference" "C82"
			(at 0 0 90)
			(layer "B.SilkS")
			(hide yes)
			(effects
				(font
					(size 1.27 1.27)
				)
				(justify mirror)
			)
		)
		(property "Value" ""
			(at 0 0 90)
			(layer "B.Fab")
			(effects
				(font
					(size 1.27 1.27)
				)
				(justify mirror)
			)
		)
		(duplicate_pad_numbers_are_jumpers no)
		(fp_line
			(start -1.524 0.762)
			(end 1.524 0.762)
			(stroke
				(width 0.1524)
				(type default)
			)
			(layer "B.SilkS")
		)
		(fp_line
			(start 1.524 0.762)
			(end 1.524 -0.762)
			(stroke
				(width 0.1524)
				(type default)
			)
			(layer "B.SilkS")
		)
		(fp_line
			(start -1.524 -0.762)
			(end -1.524 0.762)
			(stroke
				(width 0.1524)
				(type default)
			)
			(layer "B.SilkS")
		)
		(fp_line
			(start 1.524 -0.762)
			(end -1.524 -0.762)
			(stroke
				(width 0.1524)
				(type default)
			)
			(layer "B.SilkS")
		)
		(fp_line
			(start -1.1049 0.724916)
			(end -1.1049 -0.724916)
			(stroke
				(width 0.1)
				(type default)
			)
			(layer "B.Fab")
		)
		(fp_line
			(start 1.1049 0.724916)
			(end -1.1049 0.724916)
			(stroke
				(width 0.1)
				(type default)
			)
			(layer "B.Fab")
		)
		(fp_line
			(start -1.1049 -0.724916)
			(end 1.1049 -0.724916)
			(stroke
				(width 0.1)
				(type default)
			)
			(layer "B.Fab")
		)
		(fp_line
			(start 1.1049 -0.724916)
			(end 1.1049 0.724916)
			(stroke
				(width 0.1)
				(type default)
			)
			(layer "B.Fab")
		)
		(pad "1" smd rect
			(at 0.889 0 270)
			(size 1.016 1.27)
			(layers "B.Cu" "B.Mask" "B.Paste")
			(net "P12V_S3_AUX_CPU1_NVDIMM")
		)
		(pad "2" smd rect
			(at -0.889 0 270)
			(size 1.016 1.27)
			(layers "B.Cu" "B.Mask" "B.Paste")
			(net "GND")
		)
	)
	(footprint ""
		(layer "B.Cu")
		(at 108.019596 -324.792086 -90)
		(property "Reference" "PC575_P1_2"
			(at 0 0 90)
			(layer "B.SilkS")
			(hide yes)
			(effects
				(font
					(size 1.27 1.27)
				)
				(justify mirror)
			)
		)
		(property "Value" ""
			(at 0 0 90)
			(layer "B.Fab")
			(effects
				(font
					(size 1.27 1.27)
				)
				(justify mirror)
			)
		)
		(duplicate_pad_numbers_are_jumpers no)
		(fp_line
			(start -1.524 0.762)
			(end 1.524 0.762)
			(stroke
				(width 0.1524)
				(type default)
			)
			(layer "B.SilkS")
		)
		(fp_line
			(start 1.524 0.762)
			(end 1.524 -0.762)
			(stroke
				(width 0.1524)
				(type default)
			)
			(layer "B.SilkS")
		)
		(fp_line
			(start -1.524 -0.762)
			(end -1.524 0.762)
			(stroke
				(width 0.1524)
				(type default)
			)
			(layer "B.SilkS")
		)
		(fp_line
			(start 1.524 -0.762)
			(end -1.524 -0.762)
			(stroke
				(width 0.1524)
				(type default)
			)
			(layer "B.SilkS")
		)
		(fp_line
			(start -1.1049 0.724916)
			(end -1.1049 -0.724916)
			(stroke
				(width 0.1)
				(type default)
			)
			(layer "B.Fab")
		)
		(fp_line
			(start 1.1049 0.724916)
			(end -1.1049 0.724916)
			(stroke
				(width 0.1)
				(type default)
			)
			(layer "B.Fab")
		)
		(fp_line
			(start -1.1049 -0.724916)
			(end 1.1049 -0.724916)
			(stroke
				(width 0.1)
				(type default)
			)
			(layer "B.Fab")
		)
		(fp_line
			(start 1.1049 -0.724916)
			(end 1.1049 0.724916)
			(stroke
				(width 0.1)
				(type default)
			)
			(layer "B.Fab")
		)
		(pad "1" smd rect
			(at 0.889 0 270)
			(size 1.016 1.27)
			(layers "B.Cu" "B.Mask" "B.Paste")
			(net "PVCCIN_CPU1")
		)
		(pad "2" smd rect
			(at -0.889 0 270)
			(size 1.016 1.27)
			(layers "B.Cu" "B.Mask" "B.Paste")
			(net "GND")
		)
	)
	(footprint ""
		(layer "B.Cu")
		(at 69.342 -188.469016 -90)
		(property "Reference" "R557"
			(at 0 0 90)
			(layer "B.SilkS")
			(hide yes)
			(effects
				(font
					(size 1.27 1.27)
				)
				(justify mirror)
			)
		)
		(property "Value" ""
			(at 0 0 90)
			(layer "B.Fab")
			(effects
				(font
					(size 1.27 1.27)
				)
				(justify mirror)
			)
		)
		(duplicate_pad_numbers_are_jumpers no)
		(fp_line
			(start -0.7874 0.4064)
			(end 0.7874 0.4064)
			(stroke
				(width 0.1524)
				(type default)
			)
			(layer "B.SilkS")
		)
		(fp_line
			(start 0.7874 0.4064)
			(end 0.7874 -0.4064)
			(stroke
				(width 0.1524)
				(type default)
			)
			(layer "B.SilkS")
		)
		(fp_line
			(start -0.7874 -0.4064)
			(end -0.7874 0.4064)
			(stroke
				(width 0.1524)
				(type default)
			)
			(layer "B.SilkS")
		)
		(fp_line
			(start 0.7874 -0.4064)
			(end -0.7874 -0.4064)
			(stroke
				(width 0.1524)
				(type default)
			)
			(layer "B.SilkS")
		)
		(fp_line
			(start -0.67945 0.3048)
			(end -0.120396 0.3048)
			(stroke
				(width 0.1)
				(type default)
			)
			(layer "B.Fab")
		)
		(fp_line
			(start -0.120396 0.3048)
			(end -0.120396 0.2794)
			(stroke
				(width 0.1)
				(type default)
			)
			(layer "B.Fab")
		)
		(fp_line
			(start 0.12065 0.3048)
			(end 0.67945 0.3048)
			(stroke
				(width 0.1)
				(type default)
			)
			(layer "B.Fab")
		)
		(fp_line
			(start 0.67945 0.3048)
			(end 0.67945 -0.305054)
			(stroke
				(width 0.1)
				(type default)
			)
			(layer "B.Fab")
		)
		(fp_line
			(start -0.120396 0.2794)
			(end 0.12065 0.2794)
			(stroke
				(width 0.1)
				(type default)
			)
			(layer "B.Fab")
		)
		(fp_line
			(start 0.12065 0.2794)
			(end 0.12065 0.3048)
			(stroke
				(width 0.1)
				(type default)
			)
			(layer "B.Fab")
		)
		(fp_line
			(start -0.12065 -0.2794)
			(end -0.12065 -0.3048)
			(stroke
				(width 0.1)
				(type default)
			)
			(layer "B.Fab")
		)
		(fp_line
			(start 0.12065 -0.2794)
			(end -0.12065 -0.2794)
			(stroke
				(width 0.1)
				(type default)
			)
			(layer "B.Fab")
		)
		(fp_line
			(start -0.67945 -0.3048)
			(end -0.67945 0.3048)
			(stroke
				(width 0.1)
				(type default)
			)
			(layer "B.Fab")
		)
		(fp_line
			(start -0.12065 -0.3048)
			(end -0.67945 -0.3048)
			(stroke
				(width 0.1)
				(type default)
			)
			(layer "B.Fab")
		)
		(fp_line
			(start 0.12065 -0.305054)
			(end 0.12065 -0.2794)
			(stroke
				(width 0.1)
				(type default)
			)
			(layer "B.Fab")
		)
		(fp_line
			(start 0.67945 -0.305054)
			(end 0.12065 -0.305054)
			(stroke
				(width 0.1)
				(type default)
			)
			(layer "B.Fab")
		)
		(pad "1" smd circle
			(at 0.40005 0 90)
			(size 0 0)
			(layers "B.Cu" "B.Mask" "B.Paste")
			(net "SVID_DIO0_CPU1_R")
		)
		(pad "2" smd circle
			(at -0.40005 0 90)
			(size 0 0)
			(layers "B.Cu" "B.Mask" "B.Paste")
			(net "PVNN_TERM_CPU1")
		)
	)
	(footprint ""
		(layer "B.Cu")
		(at 477.732344 -334.559656 180)
		(property "Reference" "DB16"
			(at 2.664968 -8.458708 270)
			(unlocked yes)
			(layer "B.SilkS")
			(effects
				(font
					(size 0.7874 0.5842)
					(thickness 0.1524)
				)
				(justify left mirror)
			)
		)
		(property "Value" ""
			(at 0 0 0)
			(layer "B.Fab")
			(effects
				(font
					(size 1.27 1.27)
				)
				(justify mirror)
			)
		)
		(duplicate_pad_numbers_are_jumpers no)
		(fp_line
			(start 3.330702 -4.771136)
			(end -3.330702 -4.771136)
			(stroke
				(width 0.1524)
				(type default)
			)
			(layer "B.SilkS")
		)
		(fp_line
			(start 0 4.011168)
			(end 3.330702 -4.771136)
			(stroke
				(width 0.1524)
				(type default)
			)
			(layer "B.SilkS")
		)
		(fp_line
			(start -3.330702 -4.771136)
			(end 0 4.011168)
			(stroke
				(width 0.1524)
				(type default)
			)
			(layer "B.SilkS")
		)
		(fp_line
			(start 3.330702 -4.771136)
			(end -3.330702 -4.771136)
			(stroke
				(width 0.1)
				(type default)
			)
			(layer "B.Fab")
		)
		(fp_line
			(start 0 4.011168)
			(end 3.330702 -4.771136)
			(stroke
				(width 0.1)
				(type default)
			)
			(layer "B.Fab")
		)
		(fp_line
			(start -3.330702 -4.771136)
			(end 0 4.011168)
			(stroke
				(width 0.1)
				(type default)
			)
			(layer "B.Fab")
		)
		(pad "1" thru_hole circle
			(at 0 0)
			(size 2.159 2.159)
			(drill 1.7018)
			(layers "*.Cu" "*.Mask")
			(remove_unused_layers no)
			(net "T1_GND")
			(clearance 0.0254)
			(thermal_gap 0.0254)
		)
		(pad "2" thru_hole circle
			(at 1.27 -3.348736)
			(size 2.159 2.159)
			(drill 1.7018)
			(layers "*.Cu" "*.Mask")
			(remove_unused_layers no)
			(net "TDR_SE_50_OHM_IN6")
			(clearance 0.0254)
			(thermal_gap 0.0254)
		)
		(pad "3" thru_hole circle
			(at -1.27 -3.348736)
			(size 2.159 2.159)
			(drill 1.7018)
			(layers "*.Cu" "*.Mask")
			(remove_unused_layers no)
			(net "TDR_SE_50_OHM_IN6")
			(clearance 0.0254)
			(thermal_gap 0.0254)
		)
	)
	(footprint ""
		(layer "B.Cu")
		(at 127.8001 -18.534888 -90)
		(property "Reference" "R4287"
			(at 0 0 90)
			(layer "B.SilkS")
			(hide yes)
			(effects
				(font
					(size 1.27 1.27)
				)
				(justify mirror)
			)
		)
		(property "Value" ""
			(at 0 0 90)
			(layer "B.Fab")
			(effects
				(font
					(size 1.27 1.27)
				)
				(justify mirror)
			)
		)
		(duplicate_pad_numbers_are_jumpers no)
		(fp_line
			(start -0.7874 0.4064)
			(end 0.7874 0.4064)
			(stroke
				(width 0.1524)
				(type default)
			)
			(layer "B.SilkS")
		)
		(fp_line
			(start 0.7874 0.4064)
			(end 0.7874 -0.4064)
			(stroke
				(width 0.1524)
				(type default)
			)
			(layer "B.SilkS")
		)
		(fp_line
			(start -0.7874 -0.4064)
			(end -0.7874 0.4064)
			(stroke
				(width 0.1524)
				(type default)
			)
			(layer "B.SilkS")
		)
		(fp_line
			(start 0.7874 -0.4064)
			(end -0.7874 -0.4064)
			(stroke
				(width 0.1524)
				(type default)
			)
			(layer "B.SilkS")
		)
		(fp_line
			(start -0.67945 0.3048)
			(end -0.120396 0.3048)
			(stroke
				(width 0.1)
				(type default)
			)
			(layer "B.Fab")
		)
		(fp_line
			(start -0.120396 0.3048)
			(end -0.120396 0.2794)
			(stroke
				(width 0.1)
				(type default)
			)
			(layer "B.Fab")
		)
		(fp_line
			(start 0.12065 0.3048)
			(end 0.67945 0.3048)
			(stroke
				(width 0.1)
				(type default)
			)
			(layer "B.Fab")
		)
		(fp_line
			(start 0.67945 0.3048)
			(end 0.67945 -0.305054)
			(stroke
				(width 0.1)
				(type default)
			)
			(layer "B.Fab")
		)
		(fp_line
			(start -0.120396 0.2794)
			(end 0.12065 0.2794)
			(stroke
				(width 0.1)
				(type default)
			)
			(layer "B.Fab")
		)
		(fp_line
			(start 0.12065 0.2794)
			(end 0.12065 0.3048)
			(stroke
				(width 0.1)
				(type default)
			)
			(layer "B.Fab")
		)
		(fp_line
			(start -0.12065 -0.2794)
			(end -0.12065 -0.3048)
			(stroke
				(width 0.1)
				(type default)
			)
			(layer "B.Fab")
		)
		(fp_line
			(start 0.12065 -0.2794)
			(end -0.12065 -0.2794)
			(stroke
				(width 0.1)
				(type default)
			)
			(layer "B.Fab")
		)
		(fp_line
			(start -0.67945 -0.3048)
			(end -0.67945 0.3048)
			(stroke
				(width 0.1)
				(type default)
			)
			(layer "B.Fab")
		)
		(fp_line
			(start -0.12065 -0.3048)
			(end -0.67945 -0.3048)
			(stroke
				(width 0.1)
				(type default)
			)
			(layer "B.Fab")
		)
		(fp_line
			(start 0.12065 -0.305054)
			(end 0.12065 -0.2794)
			(stroke
				(width 0.1)
				(type default)
			)
			(layer "B.Fab")
		)
		(fp_line
			(start 0.67945 -0.305054)
			(end 0.12065 -0.305054)
			(stroke
				(width 0.1)
				(type default)
			)
			(layer "B.Fab")
		)
		(pad "1" smd circle
			(at 0.40005 0 90)
			(size 0 0)
			(layers "B.Cu" "B.Mask" "B.Paste")
			(net "P3V3_AUX")
		)
		(pad "2" smd circle
			(at -0.40005 0 90)
			(size 0 0)
			(layers "B.Cu" "B.Mask" "B.Paste")
			(net "FM_USB3_1_SWA")
		)
	)
)
